(kicad_pcb
	(version 20241229)
	(generator "pcbnew")
	(generator_version "9.0")
	(general
		(thickness 1.711)
		(legacy_teardrops no)
	)
	(paper "A4")
	(title_block
		(title "Antmicro Baseboard for Jetson AGX Thor")
		(date "2026-02-18")
		(rev "1.1.0")
		(company "Antmicro Ltd")
		(comment 1 "www.antmicro.com")
		(comment 9 "footprints 271-274 of 1170")
	)
	(layers
		(0 "F.Cu" signal)
		(4 "In1.Cu" signal)
		(6 "In2.Cu" signal)
		(8 "In3.Cu" signal)
		(10 "In4.Cu" jumper)
		(12 "In5.Cu" signal)
		(14 "In6.Cu" signal)
		(16 "In7.Cu" signal)
		(18 "In8.Cu" signal)
		(2 "B.Cu" signal)
		(9 "F.Adhes" user "F.Adhesive")
		(11 "B.Adhes" user "B.Adhesive")
		(13 "F.Paste" user)
		(15 "B.Paste" user)
		(5 "F.SilkS" user "F.Silkscreen")
		(7 "B.SilkS" user "B.Silkscreen")
		(1 "F.Mask" user)
		(3 "B.Mask" user)
		(17 "Dwgs.User" user "User.Drawings")
		(19 "Cmts.User" user "User.Comments")
		(21 "Eco1.User" user "User.Eco1")
		(23 "Eco2.User" user "User.Eco2")
		(25 "Edge.Cuts" user)
		(27 "Margin" user)
		(31 "F.CrtYd" user "F.Courtyard")
		(29 "B.CrtYd" user "B.Courtyard")
		(35 "F.Fab" user)
		(33 "B.Fab" user)
	)
	(footprint "antmicro-footprints:C_0603_1608Metric_EIA"
		(layer "F.Cu")
		(at 177.75 113.59 -90)
		(descr "Capacitor SMD 0603, IPC-7351 Density Level A")
		(tags "Capacitor 0603")
		(property "Reference" "C66"
			(at 1.01 7.45 90)
			(layer "F.SilkS")
			(effects
				(font
					(size 0.7 0.7)
					(thickness 0.15)
				)
				(justify left bottom)
			)
		)
		(property "Value" "C_22u_16V_0603"
			(at -1.42757 1.770288 90)
			(layer "F.Fab")
			(effects
				(font
					(size 0.7 0.7)
					(thickness 0.15)
				)
				(justify right top)
			)
		)
		(property "Datasheet" "https://product.samsungsem.com/mlcc/CL10A226MO7JZN.do"
			(at 0 0 90)
			(layer "F.Fab")
			(hide yes)
			(effects
				(font
					(size 1.27 1.27)
					(thickness 0.15)
				)
			)
		)
		(property "Description" "SMD Multilayer Ceramic Capacitor"
			(at 0 0 90)
			(layer "F.Fab")
			(hide yes)
			(effects
				(font
					(size 1.27 1.27)
					(thickness 0.15)
				)
			)
		)
		(property "Manufacturer" "Samsung Electro-Mechanics"
			(at 0 0 270)
			(unlocked yes)
			(layer "F.Fab")
			(hide yes)
			(effects
				(font
					(size 1 1)
					(thickness 0.15)
				)
			)
		)
		(property "MPN" "CL10A226MO7JZNC"
			(at 0 0 270)
			(unlocked yes)
			(layer "F.Fab")
			(hide yes)
			(effects
				(font
					(size 1 1)
					(thickness 0.15)
				)
			)
		)
		(property "Val" "22u"
			(at 0 0 270)
			(unlocked yes)
			(layer "F.Fab")
			(hide yes)
			(effects
				(font
					(size 1 1)
					(thickness 0.15)
				)
			)
		)
		(property "License" "Apache-2.0"
			(at 0 0 270)
			(unlocked yes)
			(layer "F.Fab")
			(hide yes)
			(effects
				(font
					(size 1 1)
					(thickness 0.15)
				)
			)
		)
		(property "Author" "Antmicro"
			(at 0 0 270)
			(unlocked yes)
			(layer "F.Fab")
			(hide yes)
			(effects
				(font
					(size 1 1)
					(thickness 0.15)
				)
			)
		)
		(property "Voltage" "16V"
			(at 0 0 270)
			(unlocked yes)
			(layer "F.Fab")
			(hide yes)
			(effects
				(font
					(size 1 1)
					(thickness 0.15)
				)
			)
		)
		(property "Dielectric" ""
			(at 0 0 270)
			(unlocked yes)
			(layer "F.Fab")
			(hide yes)
			(effects
				(font
					(size 1 1)
					(thickness 0.15)
				)
			)
		)
		(sheetname "/DCDC/")
		(sheetfile "dcdc.kicad_sch")
		(attr smd)
		(fp_line
			(start -0.15 0.55)
			(end 0.15 0.55)
			(stroke
				(width 0.15)
				(type solid)
			)
			(layer "F.SilkS")
		)
		(fp_line
			(start -0.15 -0.55)
			(end 0.15 -0.55)
			(stroke
				(width 0.15)
				(type solid)
			)
			(layer "F.SilkS")
		)
		(fp_rect
			(start -1.25 -0.65)
			(end 1.25 0.65)
			(stroke
				(width 0.05)
				(type solid)
			)
			(fill no)
			(layer "F.CrtYd")
		)
		(fp_rect
			(start -0.8 -0.45)
			(end 0.8 0.45)
			(stroke
				(width 0.15)
				(type solid)
			)
			(fill no)
			(layer "F.Fab")
		)
		(fp_text user "License: Apache-2.0"
			(at -1.682 5.895 90)
			(layer "F.Fab")
			(effects
				(font
					(size 0.7 0.7)
					(thickness 0.15)
				)
				(justify right top)
			)
		)
		(fp_text user "${REFERENCE}"
			(at -1.682 3.895 90)
			(layer "F.Fab")
			(effects
				(font
					(size 0.7 0.7)
					(thickness 0.15)
				)
				(justify right top)
			)
		)
		(fp_text user "Author: Antmicro"
			(at -1.682 4.894 90)
			(layer "F.Fab")
			(effects
				(font
					(size 0.7 0.7)
					(thickness 0.15)
				)
				(justify right top)
			)
		)
		(pad "1" smd roundrect
			(at -0.7 0 270)
			(size 0.8 1.1)
			(layers "F.Cu" "F.Mask" "F.Paste")
			(roundrect_rratio 0.2)
			(net 1 "GND")
			(pintype "passive")
		)
		(pad "2" smd roundrect
			(at 0.7 0 270)
			(size 0.8 1.1)
			(layers "F.Cu" "F.Mask" "F.Paste")
			(roundrect_rratio 0.2)
			(net 253 "/DCDC/5V_OUT")
			(pintype "passive")
		)
	)
	(footprint "antmicro-footprints:R_0402_1005Metric"
		(layer "F.Cu")
		(at 138.73 135.05 180)
		(descr "Resistor SMD 0402")
		(tags "resistor SMD 0402")
		(property "Reference" "R56"
			(at -1.122484 -0.772697 0)
			(layer "F.SilkS")
			(effects
				(font
					(size 0.7 0.7)
					(thickness 0.15)
				)
				(justify right top)
			)
		)
		(property "Value" "R_470R_0402"
			(at -1.011843 1.772047 0)
			(layer "F.Fab")
			(effects
				(font
					(size 0.7 0.7)
					(thickness 0.15)
				)
				(justify right top)
			)
		)
		(property "Datasheet" "https://www.bourns.com/docs/product-datasheets/cr.pdf"
			(at 0 0 0)
			(layer "F.Fab")
			(hide yes)
			(effects
				(font
					(size 1.27 1.27)
					(thickness 0.15)
				)
			)
		)
		(property "Description" "SMD Chip Resistor, 470 ohm, ± 1%, 62.5 mW, 0402 [1005 Metric], Thick Film, General Purpose"
			(at 0 0 0)
			(layer "F.Fab")
			(hide yes)
			(effects
				(font
					(size 1.27 1.27)
					(thickness 0.15)
				)
			)
		)
		(property "MPN" "CR0402-FX-4700GLF"
			(at 0 0 180)
			(unlocked yes)
			(layer "F.Fab")
			(hide yes)
			(effects
				(font
					(size 1 1)
					(thickness 0.15)
				)
			)
		)
		(property "Manufacturer" "Bourns"
			(at 0 0 180)
			(unlocked yes)
			(layer "F.Fab")
			(hide yes)
			(effects
				(font
					(size 1 1)
					(thickness 0.15)
				)
			)
		)
		(property "License" "Apache-2.0"
			(at 0 0 180)
			(unlocked yes)
			(layer "F.Fab")
			(hide yes)
			(effects
				(font
					(size 1 1)
					(thickness 0.15)
				)
			)
		)
		(property "Author" "Antmicro"
			(at 0 0 180)
			(unlocked yes)
			(layer "F.Fab")
			(hide yes)
			(effects
				(font
					(size 1 1)
					(thickness 0.15)
				)
			)
		)
		(property "Val" "470R"
			(at 0 0 180)
			(unlocked yes)
			(layer "F.Fab")
			(hide yes)
			(effects
				(font
					(size 1 1)
					(thickness 0.15)
				)
			)
		)
		(property "Tolerance" "1%"
			(at 0 0 180)
			(unlocked yes)
			(layer "F.Fab")
			(hide yes)
			(effects
				(font
					(size 1 1)
					(thickness 0.15)
				)
			)
		)
		(sheetname "/SoM_Power/")
		(sheetfile "som_power.kicad_sch")
		(attr smd)
		(fp_rect
			(start -0.925 -0.47)
			(end 0.925 0.47)
			(stroke
				(width 0.05)
				(type default)
			)
			(fill no)
			(layer "F.CrtYd")
		)
		(fp_rect
			(start -0.5 -0.25)
			(end 0.5 0.25)
			(stroke
				(width 0.15)
				(type solid)
			)
			(fill no)
			(layer "F.Fab")
		)
		(fp_text user "License: Apache-2.0"
			(at -0.95 5.169 0)
			(layer "F.Fab")
			(effects
				(font
					(size 0.7 0.7)
					(thickness 0.15)
				)
				(justify right top)
			)
		)
		(fp_text user "Author: Antmicro"
			(at -0.95 4.169 0)
			(layer "F.Fab")
			(effects
				(font
					(size 0.7 0.7)
					(thickness 0.15)
				)
				(justify right top)
			)
		)
		(fp_text user "${REFERENCE}"
			(at -0.95 3.168 0)
			(layer "F.Fab")
			(effects
				(font
					(size 0.7 0.7)
					(thickness 0.15)
				)
				(justify right top)
			)
		)
		(pad "1" smd roundrect
			(at -0.48 0 180)
			(size 0.59 0.64)
			(layers "F.Cu" "F.Mask" "F.Paste")
			(roundrect_rratio 0.25)
			(net 885 "Net-(Q10-D)")
			(pintype "passive")
		)
		(pad "2" smd roundrect
			(at 0.48 0 180)
			(size 0.59 0.64)
			(layers "F.Cu" "F.Mask" "F.Paste")
			(roundrect_rratio 0.25)
			(net 5 "+5V")
			(pintype "passive")
		)
	)
	(footprint "antmicro-footprints:USON-10_2.5x1mm_P0.5mm"
		(layer "F.Cu")
		(at 203.487 111.3)
		(descr "USON-10 2.5x1mm_ Pitch 0.5mm")
		(tags "USON-10 2.5x1mm Pitch 0.5mm")
		(property "Reference" "U4"
			(at 0.018 -1.7 0)
			(layer "F.SilkS")
			(effects
				(font
					(size 0.7 0.7)
					(thickness 0.15)
				)
				(justify left bottom)
			)
		)
		(property "Value" "TPD4E05U06QDQARQ1"
			(at 0.018 2.499 0)
			(layer "F.Fab")
			(effects
				(font
					(size 0.7 0.7)
					(thickness 0.15)
				)
				(justify left bottom)
			)
		)
		(property "Datasheet" "https://www.ti.com/lit/ds/symlink/tpd4e05u06-q1.pdf?HQS=dis-mous-null-mousermode-dsf-pf-null-wwe&ts=1663591265741&ref_url=https%253A%252F%252Fwww.mouser.com%252F"
			(at 0 0 0)
			(layer "F.Fab")
			(hide yes)
			(effects
				(font
					(size 1.27 1.27)
					(thickness 0.15)
				)
			)
		)
		(property "Description" "TVS diode array, 12 kV, USON-10, 5.5 V, 0.5 pF"
			(at 0 0 0)
			(layer "F.Fab")
			(hide yes)
			(effects
				(font
					(size 1.27 1.27)
					(thickness 0.15)
				)
			)
		)
		(property "Manufacturer" "Texas Instruments"
			(at 0 0 0)
			(unlocked yes)
			(layer "F.Fab")
			(hide yes)
			(effects
				(font
					(size 1 1)
					(thickness 0.15)
				)
			)
		)
		(property "MPN" "TPD4E05U06QDQARQ1"
			(at 0 0 0)
			(unlocked yes)
			(layer "F.Fab")
			(hide yes)
			(effects
				(font
					(size 1 1)
					(thickness 0.15)
				)
			)
		)
		(property "Author" "Antmicro"
			(at 0 0 0)
			(unlocked yes)
			(layer "F.Fab")
			(hide yes)
			(effects
				(font
					(size 1 1)
					(thickness 0.15)
				)
			)
		)
		(property "License" "Apache-2.0"
			(at 0 0 0)
			(unlocked yes)
			(layer "F.Fab")
			(hide yes)
			(effects
				(font
					(size 1 1)
					(thickness 0.15)
				)
			)
		)
		(sheetname "/SoM_Power/")
		(sheetfile "som_power.kicad_sch")
		(attr smd exclude_from_pos_files exclude_from_bom dnp)
		(fp_line
			(start 0.498 -1.401)
			(end -0.5 -1.401)
			(stroke
				(width 0.15)
				(type solid)
			)
			(layer "F.SilkS")
		)
		(fp_line
			(start 0.498 1.398)
			(end -0.5 1.398)
			(stroke
				(width 0.15)
				(type solid)
			)
			(layer "F.SilkS")
		)
		(fp_circle
			(center -0.68 -1.27)
			(end -0.63 -1.27)
			(stroke
				(width 0.15)
				(type solid)
			)
			(fill yes)
			(layer "F.SilkS")
		)
		(fp_rect
			(start -0.8 -1.5)
			(end 0.8 1.499)
			(stroke
				(width 0.05)
				(type solid)
			)
			(fill no)
			(layer "F.CrtYd")
		)
		(fp_line
			(start -0.5 -1)
			(end -0.5 1.249)
			(stroke
				(width 0.15)
				(type solid)
			)
			(layer "F.Fab")
		)
		(fp_line
			(start -0.5 1.249)
			(end 0.498 1.249)
			(stroke
				(width 0.15)
				(type solid)
			)
			(layer "F.Fab")
		)
		(fp_line
			(start -0.25 -1.25)
			(end -0.5 -1)
			(stroke
				(width 0.15)
				(type solid)
			)
			(layer "F.Fab")
		)
		(fp_line
			(start 0.498 -1.25)
			(end -0.25 -1.25)
			(stroke
				(width 0.15)
				(type solid)
			)
			(layer "F.Fab")
		)
		(fp_line
			(start 0.498 -1.25)
			(end 0.498 1.249)
			(stroke
				(width 0.15)
				(type solid)
			)
			(layer "F.Fab")
		)
		(fp_text user "Author: Antmicro"
			(at -0.802 5.7 0)
			(layer "F.Fab")
			(effects
				(font
					(size 0.7 0.7)
					(thickness 0.15)
				)
				(justify left bottom)
			)
		)
		(fp_text user "${REFERENCE}"
			(at -0.802 4.498 0)
			(layer "F.Fab")
			(effects
				(font
					(size 0.7 0.7)
					(thickness 0.15)
				)
				(justify left bottom)
			)
		)
		(fp_text user "License: Apache-2.0"
			(at -0.802 6.9 0)
			(layer "F.Fab")
			(effects
				(font
					(size 0.7 0.7)
					(thickness 0.15)
				)
				(justify left bottom)
			)
		)
		(pad "1" smd roundrect
			(at -0.387 -1 270)
			(size 0.25 0.55)
			(layers "F.Cu" "F.Mask" "F.Paste")
			(roundrect_rratio 0.25)
			(net 610 "/SoM_Power/~{PWR_BTN}")
			(pintype "passive")
		)
		(pad "2" smd roundrect
			(at -0.387 -0.5 270)
			(size 0.25 0.55)
			(layers "F.Cu" "F.Mask" "F.Paste")
			(roundrect_rratio 0.25)
			(net 702 "/SoM_Power/~{SYS_RESET}")
			(pintype "passive")
		)
		(pad "3" smd roundrect
			(at -0.387 0 270)
			(size 0.4 0.55)
			(layers "F.Cu" "F.Mask" "F.Paste")
			(roundrect_rratio 0.25)
			(net 1 "GND")
			(pintype "power_in")
		)
		(pad "4" smd roundrect
			(at -0.387 0.498 270)
			(size 0.25 0.55)
			(layers "F.Cu" "F.Mask" "F.Paste")
			(roundrect_rratio 0.25)
			(net 495 "/SoM_Power/~{FORCE_RECOVERY}")
			(pintype "passive")
		)
		(pad "5" smd roundrect
			(at -0.387 0.998 270)
			(size 0.25 0.55)
			(layers "F.Cu" "F.Mask" "F.Paste")
			(roundrect_rratio 0.25)
			(net 1398 "unconnected-(U4-Pad5)")
			(pintype "passive+no_connect")
		)
		(pad "6" smd roundrect
			(at 0.385 0.998 270)
			(size 0.25 0.55)
			(layers "F.Cu" "F.Mask" "F.Paste")
			(roundrect_rratio 0.25)
			(net 1399 "unconnected-(U4-Pad5)_1")
			(pintype "passive+no_connect")
		)
		(pad "7" smd roundrect
			(at 0.385 0.498 270)
			(size 0.25 0.55)
			(layers "F.Cu" "F.Mask" "F.Paste")
			(roundrect_rratio 0.25)
			(net 495 "/SoM_Power/~{FORCE_RECOVERY}")
			(pintype "passive")
		)
		(pad "8" smd roundrect
			(at 0.385 0 270)
			(size 0.4 0.55)
			(layers "F.Cu" "F.Mask" "F.Paste")
			(roundrect_rratio 0.25)
			(net 1 "GND")
			(pintype "passive")
		)
		(pad "9" smd roundrect
			(at 0.385 -0.5 270)
			(size 0.25 0.55)
			(layers "F.Cu" "F.Mask" "F.Paste")
			(roundrect_rratio 0.25)
			(net 702 "/SoM_Power/~{SYS_RESET}")
			(pintype "passive")
		)
		(pad "10" smd roundrect
			(at 0.385 -1 270)
			(size 0.25 0.55)
			(layers "F.Cu" "F.Mask" "F.Paste")
			(roundrect_rratio 0.25)
			(net 610 "/SoM_Power/~{PWR_BTN}")
			(pintype "passive")
		)
	)
	(footprint "antmicro-footprints:R_0402_1005Metric"
		(layer "F.Cu")
		(at 171.254468 133.12 90)
		(descr "Resistor SMD 0402")
		(tags "resistor SMD 0402")
		(property "Reference" "R316"
			(at -1.28 3.545532 90)
			(layer "F.SilkS")
			(effects
				(font
					(size 0.7 0.7)
					(thickness 0.15)
				)
				(justify left bottom)
			)
		)
		(property "Value" "R_27R_0402"
			(at -1.011843 1.772047 90)
			(layer "F.Fab")
			(effects
				(font
					(size 0.7 0.7)
					(thickness 0.15)
				)
				(justify left bottom)
			)
		)
		(property "Datasheet" "https://www.bourns.com/docs/product-datasheets/cr.pdf"
			(at 0 0 90)
			(layer "F.Fab")
			(hide yes)
			(effects
				(font
					(size 1.27 1.27)
					(thickness 0.15)
				)
			)
		)
		(property "Description" "SMD Chip Resistor, 27 ohm, ± 1%, 63 mW, 0402 [1005 Metric], Thick Film, General Purpose"
			(at 0 0 90)
			(layer "F.Fab")
			(hide yes)
			(effects
				(font
					(size 1.27 1.27)
					(thickness 0.15)
				)
			)
		)
		(property "MPN" "CR0402-FX-27R0GLF"
			(at 0 0 90)
			(unlocked yes)
			(layer "F.Fab")
			(hide yes)
			(effects
				(font
					(size 1 1)
					(thickness 0.15)
				)
			)
		)
		(property "Manufacturer" "Bourns"
			(at 0 0 90)
			(unlocked yes)
			(layer "F.Fab")
			(hide yes)
			(effects
				(font
					(size 1 1)
					(thickness 0.15)
				)
			)
		)
		(property "License" "Apache-2.0"
			(at 0 0 90)
			(unlocked yes)
			(layer "F.Fab")
			(hide yes)
			(effects
				(font
					(size 1 1)
					(thickness 0.15)
				)
			)
		)
		(property "Author" "Antmicro"
			(at 0 0 90)
			(unlocked yes)
			(layer "F.Fab")
			(hide yes)
			(effects
				(font
					(size 1 1)
					(thickness 0.15)
				)
			)
		)
		(property "Val" "27R"
			(at 0 0 90)
			(unlocked yes)
			(layer "F.Fab")
			(hide yes)
			(effects
				(font
					(size 1 1)
					(thickness 0.15)
				)
			)
		)
		(property "Tolerance" "1%"
			(at 0 0 90)
			(unlocked yes)
			(layer "F.Fab")
			(hide yes)
			(effects
				(font
					(size 1 1)
					(thickness 0.15)
				)
			)
		)
		(sheetname "/DCDC/")
		(sheetfile "dcdc.kicad_sch")
		(attr smd)
		(fp_rect
			(start -0.925 -0.47)
			(end 0.925 0.47)
			(stroke
				(width 0.05)
				(type default)
			)
			(fill no)
			(layer "F.CrtYd")
		)
		(fp_rect
			(start -0.5 -0.25)
			(end 0.5 0.25)
			(stroke
				(width 0.15)
				(type solid)
			)
			(fill no)
			(layer "F.Fab")
		)
		(fp_text user "License: Apache-2.0"
			(at -0.95 5.169 90)
			(layer "F.Fab")
			(effects
				(font
					(size 0.7 0.7)
					(thickness 0.15)
				)
				(justify left bottom)
			)
		)
		(fp_text user "Author: Antmicro"
			(at -0.95 4.169 90)
			(layer "F.Fab")
			(effects
				(font
					(size 0.7 0.7)
					(thickness 0.15)
				)
				(justify left bottom)
			)
		)
		(fp_text user "${REFERENCE}"
			(at -0.95 3.168 90)
			(layer "F.Fab")
			(effects
				(font
					(size 0.7 0.7)
					(thickness 0.15)
				)
				(justify left bottom)
			)
		)
		(pad "1" smd roundrect
			(at -0.48 0 90)
			(size 0.59 0.64)
			(layers "F.Cu" "F.Mask" "F.Paste")
			(roundrect_rratio 0.25)
			(net 1282 "Net-(U60-IN+)")
			(pintype "passive")
		)
		(pad "2" smd roundrect
			(at 0.48 0 90)
			(size 0.59 0.64)
			(layers "F.Cu" "F.Mask" "F.Paste")
			(roundrect_rratio 0.25)
			(net 567 "/DCDC/3V3_OUT")
			(pintype "passive")
		)
	)
)
